# T6G (Grand Teton) — schematic netlist excerpt (pin names and nets, part order shuffled) for the footprints in the layout excerpt that follows; sources: Cadence DE-HDL packaged netlist, KiCad conversion of 04192023_DAF0TMB3IC0_F0TG_MB_C_brd_V02_OCP.brd

R248  Q_RES  33 5% CHIP  pkg 0402LF  page 28 : A = FM_CPU0_SLP_S5_N ; B = CPU0_SLP_S5_N
R2914  Q_RES  4.7K 5% EMPTY  pkg 0402LF  page 128 : A = P3V3_AUX ; B = FM_SWB_PWR_EN_R1_BUF

(kicad_pcb
	(version 20260206)
	(generator "pcbnew")
	(generator_version "10.0")
	(general
		(thickness 1.6)
		(legacy_teardrops no)
	)
	(paper "A4")
	(title_block
		(title "04192023_DAF0TMB3IC0_F0TG_MB_C_brd_V02_OCP.brd")
		(comment 1 "Grand Teton / footprints 1971-1972 of 8354")
	)
	(layers
		(0 "F.Cu" signal "TOP")
		(4 "In1.Cu" signal "GND")
		(6 "In2.Cu" signal "IN1")
		(8 "In3.Cu" signal "GND1")
		(10 "In4.Cu" signal "IN2")
		(12 "In5.Cu" signal "GND2")
		(14 "In6.Cu" signal "IN3")
		(16 "In7.Cu" signal "GND3")
		(18 "In8.Cu" signal "VCC")
		(20 "In9.Cu" signal "VCC1")
		(22 "In10.Cu" signal "GND4")
		(24 "In11.Cu" signal "IN4")
		(26 "In12.Cu" signal "GND5")
		(28 "In13.Cu" signal "IN5")
		(30 "In14.Cu" signal "GND6")
		(32 "In15.Cu" signal "IN6")
		(34 "In16.Cu" signal "GND7")
		(2 "B.Cu" signal "BOTTOM")
		(9 "F.Adhes" user "F.Adhesive")
		(11 "B.Adhes" user "B.Adhesive")
		(13 "F.Paste" user "Package Geometry/Pastemask Top")
		(15 "B.Paste" user "Package Geometry/Pastemask Bottom")
		(5 "F.SilkS" user "Ref Des/Silkscreen Top")
		(7 "B.SilkS" user "Ref Des/Silkscreen Bottom")
		(1 "F.Mask" user "Board Geometry/Soldermask Top")
		(3 "B.Mask" user "Board Geometry/Soldermask Bottom")
		(17 "Dwgs.User" user "User.Drawings")
		(19 "Cmts.User" user "User.Comments")
		(21 "Eco1.User" user "User.Eco1")
		(23 "Eco2.User" user "User.Eco2")
		(25 "Edge.Cuts" user "Board Geometry/Outline")
		(27 "Margin" user)
		(31 "F.CrtYd" user "Package Geometry/Place Bound Top")
		(29 "B.CrtYd" user "Package Geometry/Place Bound Bottom")
		(35 "F.Fab" user "Ref Des/Assembly Top")
		(33 "B.Fab" user "Ref Des/Assembly Bottom")
	)
	(footprint ""
		(layer "F.Cu")
		(at 40.31996 -434.086 90)
		(property "Reference" "R2914"
			(at 0 0 90)
			(layer "F.SilkS")
			(hide yes)
			(effects
				(font
					(size 1.27 1.27)
				)
			)
		)
		(property "Value" ""
			(at 0 0 90)
			(layer "F.Fab")
			(effects
				(font
					(size 1.27 1.27)
				)
			)
		)
		(duplicate_pad_numbers_are_jumpers no)
		(fp_line
			(start 0.7874 -0.4064)
			(end 0.7874 0.4064)
			(stroke
				(width 0.1524)
				(type default)
			)
			(layer "F.SilkS")
		)
		(fp_line
			(start -0.7874 -0.4064)
			(end 0.7874 -0.4064)
			(stroke
				(width 0.1524)
				(type default)
			)
			(layer "F.SilkS")
		)
		(fp_line
			(start 0.7874 0.4064)
			(end -0.7874 0.4064)
			(stroke
				(width 0.1524)
				(type default)
			)
			(layer "F.SilkS")
		)
		(fp_line
			(start -0.7874 0.4064)
			(end -0.7874 -0.4064)
			(stroke
				(width 0.1524)
				(type default)
			)
			(layer "F.SilkS")
		)
		(fp_line
			(start -0.12065 -0.305054)
			(end -0.12065 -0.2794)
			(stroke
				(width 0.1)
				(type default)
			)
			(layer "F.Fab")
		)
		(fp_line
			(start -0.67945 -0.305054)
			(end -0.12065 -0.305054)
			(stroke
				(width 0.1)
				(type default)
			)
			(layer "F.Fab")
		)
		(fp_line
			(start 0.67945 -0.3048)
			(end 0.67945 0.3048)
			(stroke
				(width 0.1)
				(type default)
			)
			(layer "F.Fab")
		)
		(fp_line
			(start 0.12065 -0.3048)
			(end 0.67945 -0.3048)
			(stroke
				(width 0.1)
				(type default)
			)
			(layer "F.Fab")
		)
		(fp_line
			(start 0.12065 -0.2794)
			(end 0.12065 -0.3048)
			(stroke
				(width 0.1)
				(type default)
			)
			(layer "F.Fab")
		)
		(fp_line
			(start -0.12065 -0.2794)
			(end 0.12065 -0.2794)
			(stroke
				(width 0.1)
				(type default)
			)
			(layer "F.Fab")
		)
		(fp_line
			(start 0.120396 0.2794)
			(end -0.12065 0.2794)
			(stroke
				(width 0.1)
				(type default)
			)
			(layer "F.Fab")
		)
		(fp_line
			(start -0.12065 0.2794)
			(end -0.12065 0.3048)
			(stroke
				(width 0.1)
				(type default)
			)
			(layer "F.Fab")
		)
		(fp_line
			(start 0.67945 0.3048)
			(end 0.120396 0.3048)
			(stroke
				(width 0.1)
				(type default)
			)
			(layer "F.Fab")
		)
		(fp_line
			(start 0.120396 0.3048)
			(end 0.120396 0.2794)
			(stroke
				(width 0.1)
				(type default)
			)
			(layer "F.Fab")
		)
		(fp_line
			(start -0.12065 0.3048)
			(end -0.67945 0.3048)
			(stroke
				(width 0.1)
				(type default)
			)
			(layer "F.Fab")
		)
		(fp_line
			(start -0.67945 0.3048)
			(end -0.67945 -0.305054)
			(stroke
				(width 0.1)
				(type default)
			)
			(layer "F.Fab")
		)
		(pad "1" smd circle
			(at -0.40005 0 90)
			(size 0 0)
			(layers "F.Cu" "F.Mask" "F.Paste")
			(net "P3V3_AUX")
		)
		(pad "2" smd circle
			(at 0.40005 0 90)
			(size 0 0)
			(layers "F.Cu" "F.Mask" "F.Paste")
			(net "FM_SWB_PWR_EN_R1_BUF")
		)
	)
	(footprint ""
		(layer "F.Cu")
		(at 174.879 -137.632948 90)
		(property "Reference" "R248"
			(at 0 0 90)
			(layer "F.SilkS")
			(hide yes)
			(effects
				(font
					(size 1.27 1.27)
				)
			)
		)
		(property "Value" ""
			(at 0 0 90)
			(layer "F.Fab")
			(effects
				(font
					(size 1.27 1.27)
				)
			)
		)
		(duplicate_pad_numbers_are_jumpers no)
		(fp_line
			(start 0.7874 -0.4064)
			(end 0.7874 0.4064)
			(stroke
				(width 0.1524)
				(type default)
			)
			(layer "F.SilkS")
		)
		(fp_line
			(start -0.7874 -0.4064)
			(end 0.7874 -0.4064)
			(stroke
				(width 0.1524)
				(type default)
			)
			(layer "F.SilkS")
		)
		(fp_line
			(start 0.7874 0.4064)
			(end -0.7874 0.4064)
			(stroke
				(width 0.1524)
				(type default)
			)
			(layer "F.SilkS")
		)
		(fp_line
			(start -0.7874 0.4064)
			(end -0.7874 -0.4064)
			(stroke
				(width 0.1524)
				(type default)
			)
			(layer "F.SilkS")
		)
		(fp_line
			(start -0.12065 -0.305054)
			(end -0.12065 -0.2794)
			(stroke
				(width 0.1)
				(type default)
			)
			(layer "F.Fab")
		)
		(fp_line
			(start -0.67945 -0.305054)
			(end -0.12065 -0.305054)
			(stroke
				(width 0.1)
				(type default)
			)
			(layer "F.Fab")
		)
		(fp_line
			(start 0.67945 -0.3048)
			(end 0.67945 0.3048)
			(stroke
				(width 0.1)
				(type default)
			)
			(layer "F.Fab")
		)
		(fp_line
			(start 0.12065 -0.3048)
			(end 0.67945 -0.3048)
			(stroke
				(width 0.1)
				(type default)
			)
			(layer "F.Fab")
		)
		(fp_line
			(start 0.12065 -0.2794)
			(end 0.12065 -0.3048)
			(stroke
				(width 0.1)
				(type default)
			)
			(layer "F.Fab")
		)
		(fp_line
			(start -0.12065 -0.2794)
			(end 0.12065 -0.2794)
			(stroke
				(width 0.1)
				(type default)
			)
			(layer "F.Fab")
		)
		(fp_line
			(start 0.120396 0.2794)
			(end -0.12065 0.2794)
			(stroke
				(width 0.1)
				(type default)
			)
			(layer "F.Fab")
		)
		(fp_line
			(start -0.12065 0.2794)
			(end -0.12065 0.3048)
			(stroke
				(width 0.1)
				(type default)
			)
			(layer "F.Fab")
		)
		(fp_line
			(start 0.67945 0.3048)
			(end 0.120396 0.3048)
			(stroke
				(width 0.1)
				(type default)
			)
			(layer "F.Fab")
		)
		(fp_line
			(start 0.120396 0.3048)
			(end 0.120396 0.2794)
			(stroke
				(width 0.1)
				(type default)
			)
			(layer "F.Fab")
		)
		(fp_line
			(start -0.12065 0.3048)
			(end -0.67945 0.3048)
			(stroke
				(width 0.1)
				(type default)
			)
			(layer "F.Fab")
		)
		(fp_line
			(start -0.67945 0.3048)
			(end -0.67945 -0.305054)
			(stroke
				(width 0.1)
				(type default)
			)
			(layer "F.Fab")
		)
		(pad "1" smd circle
			(at -0.40005 0 90)
			(size 0 0)
			(layers "F.Cu" "F.Mask" "F.Paste")
			(net "FM_CPU0_SLP_S5_N")
		)
		(pad "2" smd circle
			(at 0.40005 0 90)
			(size 0 0)
			(layers "F.Cu" "F.Mask" "F.Paste")
			(net "CPU0_SLP_S5_N")
		)
	)
)
